# BASEBOARD_FAB2 (Tioga Pass) — schematic netlist excerpt (pin names and nets, part order shuffled) for the footprints in the layout excerpt that follows; sources: Cadence DE-HDL packaged netlist, KiCad conversion of Wiwynn_Tioga_Pass_MB.brd

CT58  CAP  1000PF 50V 10% X7R  pkg 0402LF  page 205 : A = A_TSENSE_PVSA_CPU0 ; B = GND
C5U10  CAP  100UF 4V 20% X5R  pkg 0805  page 217 : A = PVDDQ_ABC ; B = GND
R7P13  RES  10.0K 1% CHIP  pkg 0402  page 97 : A = GND ; B = PD_CPU1_MCP01_DMON

(kicad_pcb
	(version 20260206)
	(generator "pcbnew")
	(generator_version "10.0")
	(general
		(thickness 1.6)
		(legacy_teardrops no)
	)
	(paper "A4")
	(title_block
		(title "Wiwynn_Tioga_Pass_MB.brd")
		(comment 1 "Tioga Pass / footprints 3222-3224 of 4770")
	)
	(layers
		(0 "F.Cu" signal "TOP")
		(4 "In1.Cu" signal "L2GND")
		(6 "In2.Cu" signal "L3")
		(8 "In3.Cu" signal "L4GND")
		(10 "In4.Cu" signal "L5")
		(12 "In5.Cu" signal "L6GND")
		(14 "In6.Cu" signal "L7VCC")
		(16 "In7.Cu" signal "L8VCC")
		(18 "In8.Cu" signal "L9GND")
		(20 "In9.Cu" signal "L10")
		(22 "In10.Cu" signal "L11GND")
		(24 "In11.Cu" signal "L12")
		(26 "In12.Cu" signal "L13GND")
		(2 "B.Cu" signal "BOTTOM")
		(9 "F.Adhes" user "F.Adhesive")
		(11 "B.Adhes" user "B.Adhesive")
		(13 "F.Paste" user "Package Geometry/Pastemask Top")
		(15 "B.Paste" user "Package Geometry/Pastemask Bottom")
		(5 "F.SilkS" user "Ref Des/Silkscreen Top")
		(7 "B.SilkS" user "Ref Des/Silkscreen Bottom")
		(1 "F.Mask" user "Board Geometry/Soldermask Top")
		(3 "B.Mask" user "Board Geometry/Soldermask Bottom")
		(17 "Dwgs.User" user "User.Drawings")
		(19 "Cmts.User" user "User.Comments")
		(21 "Eco1.User" user "User.Eco1")
		(23 "Eco2.User" user "User.Eco2")
		(25 "Edge.Cuts" user "Board Geometry/Outline")
		(27 "Margin" user)
		(31 "F.CrtYd" user "Package Geometry/Place Bound Top")
		(29 "B.CrtYd" user "Package Geometry/Place Bound Bottom")
		(35 "F.Fab" user "Ref Des/Assembly Top")
		(33 "B.Fab" user "Ref Des/Assembly Bottom")
	)
	(footprint ""
		(layer "B.Cu")
		(at 195.2244 -96.5708 90)
		(property "Reference" "CT58"
			(at 0.8382 -0.84963 90)
			(unlocked yes)
			(layer "B.SilkS")
			(effects
				(font
					(size 0.7874 0.5842)
					(thickness 0.1524)
				)
				(justify left mirror)
			)
		)
		(property "Value" ""
			(at 0 0 90)
			(layer "B.Fab")
			(effects
				(font
					(size 1.27 1.27)
				)
				(justify mirror)
			)
		)
		(duplicate_pad_numbers_are_jumpers no)
		(fp_poly
			(pts
				(xy -0.3048 -0.1016) (xy -0.3048 0.9906) (xy 0.3048 0.9906) (xy 0.3048 -0.1016)
			)
			(stroke
				(width 0)
				(type default)
			)
			(fill no)
			(layer "B.CrtYd")
		)
		(fp_line
			(start 0.3048 -0.1016)
			(end 0.3048 0.9906)
			(stroke
				(width 0.1)
				(type default)
			)
			(layer "B.Fab")
		)
		(fp_line
			(start -0.3048 -0.1016)
			(end 0.3048 -0.1016)
			(stroke
				(width 0.1)
				(type default)
			)
			(layer "B.Fab")
		)
		(fp_line
			(start 0.3048 0.9906)
			(end -0.3048 0.9906)
			(stroke
				(width 0.1)
				(type default)
			)
			(layer "B.Fab")
		)
		(fp_line
			(start -0.3048 0.9906)
			(end -0.3048 -0.1016)
			(stroke
				(width 0.1)
				(type default)
			)
			(layer "B.Fab")
		)
		(pad "1" smd rect
			(at 0 0 270)
			(size 0.508 0.508)
			(layers "B.Cu" "B.Mask" "B.Paste")
			(net "A_TSENSE_PVSA_CPU0")
		)
		(pad "2" smd rect
			(at 0 0.889 270)
			(size 0.508 0.508)
			(layers "B.Cu" "B.Mask" "B.Paste")
			(net "GND")
		)
		(zone
			(layer "B.Cu")
			(hatch none 0.5)
			(connect_pads
				(clearance 0)
			)
			(min_thickness 0.25)
			(keepout
				(tracks allowed)
				(vias not_allowed)
				(pads allowed)
				(copperpour not_allowed)
				(footprints allowed)
			)
			(placement
				(enabled no)
				(sheetname "")
			)
			(fill
				(thermal_gap 0.5)
				(thermal_bridge_width 0.5)
				(island_removal_mode 0)
			)
			(polygon
				(pts
					(xy 195.4784 -96.8248) (xy 195.4784 -96.3168) (xy 195.8594 -96.3168) (xy 195.8594 -96.8248)
				)
			)
		)
		(zone
			(layer "B.Cu")
			(hatch none 0.5)
			(connect_pads
				(clearance 0)
			)
			(min_thickness 0.25)
			(keepout
				(tracks not_allowed)
				(vias allowed)
				(pads allowed)
				(copperpour not_allowed)
				(footprints allowed)
			)
			(placement
				(enabled no)
				(sheetname "")
			)
			(fill
				(thermal_gap 0.5)
				(thermal_bridge_width 0.5)
				(island_removal_mode 0)
			)
			(polygon
				(pts
					(xy 195.8594 -96.8248) (xy 195.8594 -96.3168) (xy 195.4784 -96.3168) (xy 195.4784 -96.8248)
				)
			)
		)
	)
	(footprint ""
		(layer "B.Cu")
		(at 259.6642 -8.122412 90)
		(property "Reference" "C5U10"
			(at 0 0 90)
			(layer "B.SilkS")
			(hide yes)
			(effects
				(font
					(size 1.27 1.27)
				)
				(justify mirror)
			)
		)
		(property "Value" ""
			(at 0 0 90)
			(layer "B.Fab")
			(effects
				(font
					(size 1.27 1.27)
				)
				(justify mirror)
			)
		)
		(duplicate_pad_numbers_are_jumpers no)
		(fp_rect
			(start -0.7239 -0.2159)
			(end 0.7239 1.9939)
			(stroke
				(width 0)
				(type default)
			)
			(fill no)
			(layer "B.CrtYd")
		)
		(fp_line
			(start 0.7239 -0.2159)
			(end 0.7239 1.9939)
			(stroke
				(width 0.1)
				(type default)
			)
			(layer "B.Fab")
		)
		(fp_line
			(start -0.7239 -0.2159)
			(end 0.7239 -0.2159)
			(stroke
				(width 0.1)
				(type default)
			)
			(layer "B.Fab")
		)
		(fp_line
			(start 0.7239 1.9939)
			(end -0.7239 1.9939)
			(stroke
				(width 0.1)
				(type default)
			)
			(layer "B.Fab")
		)
		(fp_line
			(start -0.7239 1.9939)
			(end -0.7239 -0.2159)
			(stroke
				(width 0.1)
				(type default)
			)
			(layer "B.Fab")
		)
		(pad "1" smd rect
			(at 0 0 270)
			(size 1.27 1.016)
			(layers "B.Cu" "B.Mask" "B.Paste")
			(net "PVDDQ_ABC")
		)
		(pad "2" smd rect
			(at 0 1.778 270)
			(size 1.27 1.016)
			(layers "B.Cu" "B.Mask" "B.Paste")
			(net "GND")
		)
		(zone
			(layer "B.Cu")
			(hatch none 0.5)
			(connect_pads
				(clearance 0)
			)
			(min_thickness 0.25)
			(keepout
				(tracks not_allowed)
				(vias allowed)
				(pads allowed)
				(copperpour not_allowed)
				(footprints allowed)
			)
			(placement
				(enabled no)
				(sheetname "")
			)
			(fill
				(thermal_gap 0.5)
				(thermal_bridge_width 0.5)
				(island_removal_mode 0)
			)
			(polygon
				(pts
					(xy 260.1722 -7.487412) (xy 260.9342 -7.487412) (xy 260.9342 -8.757412) (xy 260.1722 -8.757412)
				)
			)
		)
	)
	(footprint ""
		(layer "B.Cu")
		(at 116.332 -76.454 90)
		(property "Reference" "R7P13"
			(at 0 0 90)
			(layer "B.SilkS")
			(hide yes)
			(effects
				(font
					(size 1.27 1.27)
				)
				(justify mirror)
			)
		)
		(property "Value" ""
			(at 0 0 90)
			(layer "B.Fab")
			(effects
				(font
					(size 1.27 1.27)
				)
				(justify mirror)
			)
		)
		(duplicate_pad_numbers_are_jumpers no)
		(fp_poly
			(pts
				(xy 0.2794 -0.1016) (xy -0.2794 -0.1016) (xy -0.2794 0.9906) (xy 0.2794 0.9906)
			)
			(stroke
				(width 0)
				(type default)
			)
			(fill no)
			(layer "B.CrtYd")
		)
		(fp_line
			(start 0.2794 -0.1016)
			(end 0.2794 0.9906)
			(stroke
				(width 0.1)
				(type default)
			)
			(layer "B.Fab")
		)
		(fp_line
			(start -0.2794 -0.1016)
			(end 0.2794 -0.1016)
			(stroke
				(width 0.1)
				(type default)
			)
			(layer "B.Fab")
		)
		(fp_line
			(start 0.2794 0.9906)
			(end -0.2794 0.9906)
			(stroke
				(width 0.1)
				(type default)
			)
			(layer "B.Fab")
		)
		(fp_line
			(start -0.2794 0.9906)
			(end -0.2794 -0.1016)
			(stroke
				(width 0.1)
				(type default)
			)
			(layer "B.Fab")
		)
		(pad "1" smd rect
			(at 0 0 270)
			(size 0.508 0.508)
			(layers "B.Cu" "B.Mask" "B.Paste")
			(net "GND")
		)
		(pad "2" smd rect
			(at 0 0.889 270)
			(size 0.508 0.508)
			(layers "B.Cu" "B.Mask" "B.Paste")
			(net "PD_CPU1_MCP01_DMON")
		)
		(zone
			(layer "B.Cu")
			(hatch none 0.5)
			(connect_pads
				(clearance 0)
			)
			(min_thickness 0.25)
			(keepout
				(tracks allowed)
				(vias not_allowed)
				(pads allowed)
				(copperpour not_allowed)
				(footprints allowed)
			)
			(placement
				(enabled no)
				(sheetname "")
			)
			(fill
				(thermal_gap 0.5)
				(thermal_bridge_width 0.5)
				(island_removal_mode 0)
			)
			(polygon
				(pts
					(xy 116.586 -76.708) (xy 116.586 -76.2) (xy 116.967 -76.2) (xy 116.967 -76.708)
				)
			)
		)
		(zone
			(layer "B.Cu")
			(hatch none 0.5)
			(connect_pads
				(clearance 0)
			)
			(min_thickness 0.25)
			(keepout
				(tracks not_allowed)
				(vias allowed)
				(pads allowed)
				(copperpour not_allowed)
				(footprints allowed)
			)
			(placement
				(enabled no)
				(sheetname "")
			)
			(fill
				(thermal_gap 0.5)
				(thermal_bridge_width 0.5)
				(island_removal_mode 0)
			)
			(polygon
				(pts
					(xy 116.967 -76.708) (xy 116.967 -76.2) (xy 116.586 -76.2) (xy 116.586 -76.708)
				)
			)
		)
	)
)
